# T6G (Grand Teton) — schematic netlist excerpt (pin names and nets, part order shuffled) for the footprints in the layout excerpt that follows; sources: Cadence DE-HDL packaged netlist, KiCad conversion of 04192023_DAF0TMB3IC0_F0TG_MB_C_brd_V02_OCP.brd

J38  SCONN168_ME1016810202011  IO  pkg CON_F168S2H7D_P0-6W2-95_LUH  page 131
  GND_A1  = GND
  GND_A2  = GND
  GND_A3  = GND
  GND_A4  = GND
  GND_A5  = GND
  GND_A6  = GND
  SMCLK  = SMB_OCP_SFF_3V3AUX_BUF_R_SCL
  SMDAT  = SMB_OCP_SFF_3V3AUX_BUF_R_SDA
  \smrst#\  = RST_SMB_OCP_SFF_N
  \prsnta#\  = OCP_SFF_PRSNTA_R_N
  \perst1#\  = RST_PERST1_OCP_SFF_N
  \prsntb2#\  = OCP_SFF_PRSNT2_R_N
  GND_A13  = GND
  REFCLKN1  = CLK_100M_CPU0_CLK03_DN
  REFCLKP1  = CLK_100M_CPU0_CLK03_DP
  GND_A16  = GND
  PERN0  = P5E_CPU0_G3_RX_DN<0>
  PERP0  = P5E_CPU0_G3_RX_DP<0>
  GND_A19  = GND
  PERN1  = P5E_CPU0_G3_RX_DN<1>
  PERP1  = P5E_CPU0_G3_RX_DP<1>
  GND_A22  = GND
  PERN2  = P5E_CPU0_G3_RX_DN<2>
  PERP2  = P5E_CPU0_G3_RX_DP<2>
  GND_A25  = GND
  PERN3  = P5E_CPU0_G3_RX_DN<3>
  PERP3  = P5E_CPU0_G3_RX_DP<3>
  GND_A28  = GND
  GND_A29  = GND
  PERN4  = P5E_CPU0_G3_RX_DN<4>
  PERP4  = P5E_CPU0_G3_RX_DP<4>
  GND_A32  = GND
  PERN5  = P5E_CPU0_G3_RX_DN<5>
  PERP5  = P5E_CPU0_G3_RX_DP<5>
  GND_A35  = GND
  PERN6  = P5E_CPU0_G3_RX_DN<6>
  PERP6  = P5E_CPU0_G3_RX_DP<6>
  GND_A38  = GND
  PERN7  = P5E_CPU0_G3_RX_DN<7>
  PERP7  = P5E_CPU0_G3_RX_DP<7>
  GND_A41  = GND
  \prsntb1#\  = OCP_SFF_PRSNT1_R_N
  GND_A43  = GND
  PERN8  = P5E_CPU0_G3_RX_DN<8>
  PERP8  = P5E_CPU0_G3_RX_DP<8>
  GND_A46  = GND
  PERN9  = P5E_CPU0_G3_RX_DN<9>
  PERP9  = P5E_CPU0_G3_RX_DP<9>
  GND_A49  = GND
  PERN10  = P5E_CPU0_G3_RX_DN<10>
  PERP10  = P5E_CPU0_G3_RX_DP<10>
  GND_A52  = GND
  PERN11  = P5E_CPU0_G3_RX_DN<11>
  PERP11  = P5E_CPU0_G3_RX_DP<11>
  GND_A55  = GND
  PERN12  = P5E_CPU0_G3_RX_DN<12>
  PERP12  = P5E_CPU0_G3_RX_DP<12>
  GND_A58  = GND
  PERN13  = P5E_CPU0_G3_RX_DN<13>
  PERP13  = P5E_CPU0_G3_RX_DP<13>
  GND_A61  = GND
  PERN14  = P5E_CPU0_G3_RX_DN<14>
  PERP14  = P5E_CPU0_G3_RX_DP<14>
  GND_A64  = GND
  PERN15  = P5E_CPU0_G3_RX_DN<15>
  PERP15  = P5E_CPU0_G3_RX_DP<15>
  GND_A67  = GND
  USB_DATN  = USB2_P11_DN
  USB_DATP  = USB2_P11_DP
  \pwrbrk0#\  = OCP_SFF_PWRBRK_N
  \+12v_edge_b1\  = P12V_OCP_SFF_R
  \+12v_edge_b2\  = P12V_OCP_SFF_R
  \+12v_edge_b3\  = P12V_OCP_SFF_R
  \+12v_edge_b4\  = P12V_OCP_SFF_R
  \+12v_edge_b5\  = P12V_OCP_SFF_R
  \+12v_edge_b6\  = P12V_OCP_SFF_R
  \bif0#\  = OCP_SFF_BIF0_R_N
  \bif1#\  = OCP_SFF_BIF1_R_N
  \bif2#\  = OCP_SFF_BIF2_R_N
  \perst0#\  = RST_PERST0_OCP_SFF_N
  \+3.3v_edge\  = P3V3_OCP_SFF
  AUX_PWR_EN  = OCP_SFF_AUX_PWR_EN_R
  GND_B13  = GND
  REFCLKN0  = CLK_100M_CPU0_CLK02_DN
  REFCLKP0  = CLK_100M_CPU0_CLK02_DP
  GND_B16  = GND
  PETN0  = P5E_CPU0_G3_TX_C_DP<0>
  PETP0  = P5E_CPU0_G3_TX_C_DN<0>
  GND_B19  = GND
  PETN1  = P5E_CPU0_G3_TX_C_DP<1>
  PETP1  = P5E_CPU0_G3_TX_C_DN<1>
  GND_B22  = GND
  PETN2  = P5E_CPU0_G3_TX_C_DP<2>
  PETP2  = P5E_CPU0_G3_TX_C_DN<2>
  GND_B25  = GND
  PETN3  = P5E_CPU0_G3_TX_C_DP<3>
  PETP3  = P5E_CPU0_G3_TX_C_DN<3>
  GND_B28  = GND
  GND_B29  = GND
  PETN4  = P5E_CPU0_G3_TX_C_DP<4>
  PETP4  = P5E_CPU0_G3_TX_C_DN<4>
  GND_B32  = GND
  PETN5  = P5E_CPU0_G3_TX_C_DP<5>
  PETP5  = P5E_CPU0_G3_TX_C_DN<5>
  GND_B35  = GND
  PETN6  = P5E_CPU0_G3_TX_C_DP<6>
  PETP6  = P5E_CPU0_G3_TX_C_DN<6>
  GND_B38  = GND
  PETN7  = P5E_CPU0_G3_TX_C_DP<7>
  PETP7  = P5E_CPU0_G3_TX_C_DN<7>
  GND_B41  = GND
  \prsntb0#\  = OCP_SFF_PRSNT0_R_N
  GND_B43  = GND
  PETN8  = P5E_CPU0_G3_TX_C_DP<8>
  PETP8  = P5E_CPU0_G3_TX_C_DN<8>
  GND_B46  = GND
  PETN9  = P5E_CPU0_G3_TX_C_DP<9>
  PETP9  = P5E_CPU0_G3_TX_C_DN<9>
  GND_B49  = GND
  PETN10  = P5E_CPU0_G3_TX_C_DP<10>
  PETP10  = P5E_CPU0_G3_TX_C_DN<10>
  GND_B52  = GND
  PETN11  = P5E_CPU0_G3_TX_C_DP<11>
  PETP11  = P5E_CPU0_G3_TX_C_DN<11>
  GND_B55  = GND
  PETN12  = P5E_CPU0_G3_TX_C_DP<12>
  PETP12  = P5E_CPU0_G3_TX_C_DN<12>
  GND_B58  = GND
  PETN13  = P5E_CPU0_G3_TX_C_DP<13>
  PETP13  = P5E_CPU0_G3_TX_C_DN<13>
  GND_B61  = GND
  PETN14  = P5E_CPU0_G3_TX_C_DP<14>
  PETP14  = P5E_CPU0_G3_TX_C_DN<14>
  GND_B64  = GND
  PETN15  = P5E_CPU0_G3_TX_C_DP<15>
  PETP15  = P5E_CPU0_G3_TX_C_DN<15>
  GND_B67  = GND
  RFU1_NC_B68  = TP_OCP_SFF_B68
  RFU1_NC_B69  = TP_OCP_SFF_B69
  \prsntb3#\  = OCP_SFF_PRSNT3_R_N
  G1  = GND
  G2  = GND
  G3  = GND
  G4  = GND
  G5  = GND
  \perst2#\  = RST_PERST2_OCP_SFF_N
  \perst3#\  = RST_PERST3_OCP_SFF_N
  \wake#\  = IRQ_LVC3_OCP_SFF_WAKE_N
  RBT_ARB_IN  = OCP_SFF_ISO1_RBT_ARB_IN
  RBT_ARB_OUT  = OCP_SFF_ISO2_RBT_ARB_OUT
  SLOT_ID1  = OCP_SFF_ID1
  RBT_TX_EN  = NCSI_OCP_SFF_TX_EN
  RBT_TXD1  = NCSI_OCP_SFF_TXD1
  RBT_TXD0  = NCSI_OCP_SFF_TXD0
  GND_OA10  = GND
  REFCLKN3  = CLK_100M_CPU0_CLK05_DN
  REFCLKP3  = CLK_100M_CPU0_CLK05_DP
  GND_OA13  = GND
  RBT_CLK_IN  = CLK_50M_NCSI_OCP_SFF_ISO
  NIC_PWR_GOOD  = FM_OCP_SFF_PWR_GOOD
  MAIN_PWR_EN  = OCP_SFF_MAIN_PWR_EN_R
  \ld#\  = SGPIO_OCP_SFF_LD_N
  DATA_IN  = SGPIO_OCP_SFF_DATAIN
  DATA_OUT  = SGPIO_OCP_SFF_DATAOUT
  CLK  = SGPIO_OCP_SFF_CLK
  SLOT_ID0  = OCP_SFF_ID0
  RBT_RXD1  = NCSI_OCP_SFF_RXD1
  RBT_RXD0  = NCSI_OCP_SFF_RXD0
  GND_OB10  = GND
  REFCLKN2  = CLK_100M_CPU0_CLK04_DN
  REFCLKP2  = CLK_100M_CPU0_CLK04_DP
  GND_OB13  = GND
  RBT_CRS_DV  = NCSI_OCP_SFF_CRS_DV

(kicad_pcb
	(version 20260206)
	(generator "pcbnew")
	(generator_version "10.0")
	(general
		(thickness 1.6)
		(legacy_teardrops no)
	)
	(paper "A4")
	(title_block
		(title "04192023_DAF0TMB3IC0_F0TG_MB_C_brd_V02_OCP.brd")
		(comment 1 "Grand Teton / footprint 2929 of 8354 (J38), pads 46-89 of 175")
	)
	(layers
		(0 "F.Cu" signal "TOP")
		(4 "In1.Cu" signal "GND")
		(6 "In2.Cu" signal "IN1")
		(8 "In3.Cu" signal "GND1")
		(10 "In4.Cu" signal "IN2")
		(12 "In5.Cu" signal "GND2")
		(14 "In6.Cu" signal "IN3")
		(16 "In7.Cu" signal "GND3")
		(18 "In8.Cu" signal "VCC")
		(20 "In9.Cu" signal "VCC1")
		(22 "In10.Cu" signal "GND4")
		(24 "In11.Cu" signal "IN4")
		(26 "In12.Cu" signal "GND5")
		(28 "In13.Cu" signal "IN5")
		(30 "In14.Cu" signal "GND6")
		(32 "In15.Cu" signal "IN6")
		(34 "In16.Cu" signal "GND7")
		(2 "B.Cu" signal "BOTTOM")
		(9 "F.Adhes" user "F.Adhesive")
		(11 "B.Adhes" user "B.Adhesive")
		(13 "F.Paste" user "Package Geometry/Pastemask Top")
		(15 "B.Paste" user "Package Geometry/Pastemask Bottom")
		(5 "F.SilkS" user "Ref Des/Silkscreen Top")
		(7 "B.SilkS" user "Ref Des/Silkscreen Bottom")
		(1 "F.Mask" user "Board Geometry/Soldermask Top")
		(3 "B.Mask" user "Board Geometry/Soldermask Bottom")
		(17 "Dwgs.User" user "User.Drawings")
		(19 "Cmts.User" user "User.Comments")
		(21 "Eco1.User" user "User.Eco1")
		(23 "Eco2.User" user "User.Eco2")
		(25 "Edge.Cuts" user "Board Geometry/Outline")
		(27 "Margin" user)
		(31 "F.CrtYd" user "Package Geometry/Place Bound Top")
		(29 "B.CrtYd" user "Package Geometry/Place Bound Bottom")
		(35 "F.Fab" user "Ref Des/Assembly Top")
		(33 "B.Fab" user "Ref Des/Assembly Bottom")
	)
	(footprint ""
		(layer "F.Cu")
		(at 421.901874 -5.569966 -90)
		(property "Reference" "J38"
			(at -8.103616 -20.50034 0)
			(unlocked yes)
			(layer "F.SilkS")
			(effects
				(font
					(size 0.7874 0.5842)
					(thickness 0.1524)
				)
				(justify left)
			)
		)
		(property "Value" ""
			(at 0 0 270)
			(layer "F.Fab")
			(effects
				(font
					(size 1.27 1.27)
				)
			)
		)
		(duplicate_pad_numbers_are_jumpers no)
		(pad "A44" smd rect
			(at -2.750058 15.055088 180)
			(size 0.381 1.4478)
			(layers "F.Cu" "F.Mask" "F.Paste")
			(net "P5E_CPU0_G3_RX_DN<8>")
		)
		(pad "A45" smd rect
			(at -2.750058 15.655036 180)
			(size 0.381 1.4478)
			(layers "F.Cu" "F.Mask" "F.Paste")
			(net "P5E_CPU0_G3_RX_DP<8>")
		)
		(pad "A46" smd rect
			(at -2.750058 16.254984 180)
			(size 0.381 1.4478)
			(layers "F.Cu" "F.Mask" "F.Paste")
			(net "GND")
		)
		(pad "A47" smd rect
			(at -2.750058 16.854932 180)
			(size 0.381 1.4478)
			(layers "F.Cu" "F.Mask" "F.Paste")
			(net "P5E_CPU0_G3_RX_DN<9>")
		)
		(pad "A48" smd rect
			(at -2.750058 17.45488 180)
			(size 0.381 1.4478)
			(layers "F.Cu" "F.Mask" "F.Paste")
			(net "P5E_CPU0_G3_RX_DP<9>")
		)
		(pad "A49" smd rect
			(at -2.750058 18.055082 180)
			(size 0.381 1.4478)
			(layers "F.Cu" "F.Mask" "F.Paste")
			(net "GND")
		)
		(pad "A50" smd rect
			(at -2.750058 18.65503 180)
			(size 0.381 1.4478)
			(layers "F.Cu" "F.Mask" "F.Paste")
			(net "P5E_CPU0_G3_RX_DN<10>")
		)
		(pad "A51" smd rect
			(at -2.750058 19.254978 180)
			(size 0.381 1.4478)
			(layers "F.Cu" "F.Mask" "F.Paste")
			(net "P5E_CPU0_G3_RX_DP<10>")
		)
		(pad "A52" smd rect
			(at -2.750058 19.854926 180)
			(size 0.381 1.4478)
			(layers "F.Cu" "F.Mask" "F.Paste")
			(net "GND")
		)
		(pad "A53" smd rect
			(at -2.750058 20.455128 180)
			(size 0.381 1.4478)
			(layers "F.Cu" "F.Mask" "F.Paste")
			(net "P5E_CPU0_G3_RX_DN<11>")
		)
		(pad "A54" smd rect
			(at -2.750058 21.055076 180)
			(size 0.381 1.4478)
			(layers "F.Cu" "F.Mask" "F.Paste")
			(net "P5E_CPU0_G3_RX_DP<11>")
		)
		(pad "A55" smd rect
			(at -2.750058 21.655024 180)
			(size 0.381 1.4478)
			(layers "F.Cu" "F.Mask" "F.Paste")
			(net "GND")
		)
		(pad "A56" smd rect
			(at -2.750058 22.254972 180)
			(size 0.381 1.4478)
			(layers "F.Cu" "F.Mask" "F.Paste")
			(net "P5E_CPU0_G3_RX_DN<12>")
		)
		(pad "A57" smd rect
			(at -2.750058 22.85492 180)
			(size 0.381 1.4478)
			(layers "F.Cu" "F.Mask" "F.Paste")
			(net "P5E_CPU0_G3_RX_DP<12>")
		)
		(pad "A58" smd rect
			(at -2.750058 23.455122 180)
			(size 0.381 1.4478)
			(layers "F.Cu" "F.Mask" "F.Paste")
			(net "GND")
		)
		(pad "A59" smd rect
			(at -2.750058 24.05507 180)
			(size 0.381 1.4478)
			(layers "F.Cu" "F.Mask" "F.Paste")
			(net "P5E_CPU0_G3_RX_DN<13>")
		)
		(pad "A60" smd rect
			(at -2.750058 24.655018 180)
			(size 0.381 1.4478)
			(layers "F.Cu" "F.Mask" "F.Paste")
			(net "P5E_CPU0_G3_RX_DP<13>")
		)
		(pad "A61" smd rect
			(at -2.750058 25.254966 180)
			(size 0.381 1.4478)
			(layers "F.Cu" "F.Mask" "F.Paste")
			(net "GND")
		)
		(pad "A62" smd rect
			(at -2.750058 25.854914 180)
			(size 0.381 1.4478)
			(layers "F.Cu" "F.Mask" "F.Paste")
			(net "P5E_CPU0_G3_RX_DN<14>")
		)
		(pad "A63" smd rect
			(at -2.750058 26.455116 180)
			(size 0.381 1.4478)
			(layers "F.Cu" "F.Mask" "F.Paste")
			(net "P5E_CPU0_G3_RX_DP<14>")
		)
		(pad "A64" smd rect
			(at -2.750058 27.055064 180)
			(size 0.381 1.4478)
			(layers "F.Cu" "F.Mask" "F.Paste")
			(net "GND")
		)
		(pad "A65" smd rect
			(at -2.750058 27.655012 180)
			(size 0.381 1.4478)
			(layers "F.Cu" "F.Mask" "F.Paste")
			(net "P5E_CPU0_G3_RX_DN<15>")
		)
		(pad "A66" smd rect
			(at -2.750058 28.25496 180)
			(size 0.381 1.4478)
			(layers "F.Cu" "F.Mask" "F.Paste")
			(net "P5E_CPU0_G3_RX_DP<15>")
		)
		(pad "A67" smd rect
			(at -2.750058 28.854908 180)
			(size 0.381 1.4478)
			(layers "F.Cu" "F.Mask" "F.Paste")
			(net "GND")
		)
		(pad "A68" smd rect
			(at -2.750058 29.45511 180)
			(size 0.381 1.4478)
			(layers "F.Cu" "F.Mask" "F.Paste")
			(net "USB2_P11_DN")
		)
		(pad "A69" smd rect
			(at -2.750058 30.055058 180)
			(size 0.381 1.4478)
			(layers "F.Cu" "F.Mask" "F.Paste")
			(net "USB2_P11_DP")
		)
		(pad "A70" smd rect
			(at -2.750058 30.655006 180)
			(size 0.381 1.4478)
			(layers "F.Cu" "F.Mask" "F.Paste")
			(net "OCP_SFF_PWRBRK_N")
		)
		(pad "B1" smd rect
			(at -5.700014 -18.465038 180)
			(size 0.381 1.4478)
			(layers "F.Cu" "F.Mask" "F.Paste")
			(net "P12V_OCP_SFF_R")
		)
		(pad "B2" smd rect
			(at -5.700014 -17.86509 180)
			(size 0.381 1.4478)
			(layers "F.Cu" "F.Mask" "F.Paste")
			(net "P12V_OCP_SFF_R")
		)
		(pad "B3" smd rect
			(at -5.700014 -17.264888 180)
			(size 0.381 1.4478)
			(layers "F.Cu" "F.Mask" "F.Paste")
			(net "P12V_OCP_SFF_R")
		)
		(pad "B4" smd rect
			(at -5.700014 -16.66494 180)
			(size 0.381 1.4478)
			(layers "F.Cu" "F.Mask" "F.Paste")
			(net "P12V_OCP_SFF_R")
		)
		(pad "B5" smd rect
			(at -5.700014 -16.064992 180)
			(size 0.381 1.4478)
			(layers "F.Cu" "F.Mask" "F.Paste")
			(net "P12V_OCP_SFF_R")
		)
		(pad "B6" smd rect
			(at -5.700014 -15.465044 180)
			(size 0.381 1.4478)
			(layers "F.Cu" "F.Mask" "F.Paste")
			(net "P12V_OCP_SFF_R")
		)
		(pad "B7" smd rect
			(at -5.700014 -14.865096 180)
			(size 0.381 1.4478)
			(layers "F.Cu" "F.Mask" "F.Paste")
			(net "OCP_SFF_BIF0_R_N")
		)
		(pad "B8" smd rect
			(at -5.700014 -14.264894 180)
			(size 0.381 1.4478)
			(layers "F.Cu" "F.Mask" "F.Paste")
			(net "OCP_SFF_BIF1_R_N")
		)
		(pad "B9" smd rect
			(at -5.700014 -13.664946 180)
			(size 0.381 1.4478)
			(layers "F.Cu" "F.Mask" "F.Paste")
			(net "OCP_SFF_BIF2_R_N")
		)
		(pad "B10" smd rect
			(at -5.700014 -13.064998 180)
			(size 0.381 1.4478)
			(layers "F.Cu" "F.Mask" "F.Paste")
			(net "RST_PERST0_OCP_SFF_N")
		)
		(pad "B11" smd rect
			(at -5.700014 -12.46505 180)
			(size 0.381 1.4478)
			(layers "F.Cu" "F.Mask" "F.Paste")
			(net "P3V3_OCP_SFF")
		)
		(pad "B12" smd rect
			(at -5.700014 -11.865102 180)
			(size 0.381 1.4478)
			(layers "F.Cu" "F.Mask" "F.Paste")
			(net "OCP_SFF_AUX_PWR_EN_R")
		)
		(pad "B13" smd rect
			(at -5.700014 -11.2649 180)
			(size 0.381 1.4478)
			(layers "F.Cu" "F.Mask" "F.Paste")
			(net "GND")
		)
		(pad "B14" smd rect
			(at -5.700014 -10.664952 180)
			(size 0.381 1.4478)
			(layers "F.Cu" "F.Mask" "F.Paste")
			(net "CLK_100M_CPU0_CLK02_DN")
		)
		(pad "B15" smd rect
			(at -5.700014 -10.065004 180)
			(size 0.381 1.4478)
			(layers "F.Cu" "F.Mask" "F.Paste")
			(net "CLK_100M_CPU0_CLK02_DP")
		)
		(pad "B16" smd rect
			(at -5.700014 -9.465056 180)
			(size 0.381 1.4478)
			(layers "F.Cu" "F.Mask" "F.Paste")
			(net "GND")
		)
		(pad "B17" smd rect
			(at -5.700014 -8.865108 180)
			(size 0.381 1.4478)
			(layers "F.Cu" "F.Mask" "F.Paste")
			(net "P5E_CPU0_G3_TX_C_DP<0>")
		)
	)
)
